# T6G (Grand Teton) — schematic netlist excerpt (pin names and nets, part order shuffled) for the footprints in the layout excerpt that follows; sources: Cadence DE-HDL packaged netlist, KiCad conversion of 04192023_DAF0TMB3IC0_F0TG_MB_C_brd_V02_OCP.brd

R109  Q_RES  1K 1% EMPTY  pkg 0402LF  page 104 : A = P3V3 ; B = PWRGD_CHGL_CPU1
C2440  Q_CAP  22UF 4V 20% X6S  pkg C0402  page 74 : A = PVDDCR_SOC_P1 ; B = GND

(kicad_pcb
	(version 20260206)
	(generator "pcbnew")
	(generator_version "10.0")
	(general
		(thickness 1.6)
		(legacy_teardrops no)
	)
	(paper "A4")
	(title_block
		(title "04192023_DAF0TMB3IC0_F0TG_MB_C_brd_V02_OCP.brd")
		(comment 1 "Grand Teton / footprints 7691-7692 of 8354")
	)
	(layers
		(0 "F.Cu" signal "TOP")
		(4 "In1.Cu" signal "GND")
		(6 "In2.Cu" signal "IN1")
		(8 "In3.Cu" signal "GND1")
		(10 "In4.Cu" signal "IN2")
		(12 "In5.Cu" signal "GND2")
		(14 "In6.Cu" signal "IN3")
		(16 "In7.Cu" signal "GND3")
		(18 "In8.Cu" signal "VCC")
		(20 "In9.Cu" signal "VCC1")
		(22 "In10.Cu" signal "GND4")
		(24 "In11.Cu" signal "IN4")
		(26 "In12.Cu" signal "GND5")
		(28 "In13.Cu" signal "IN5")
		(30 "In14.Cu" signal "GND6")
		(32 "In15.Cu" signal "IN6")
		(34 "In16.Cu" signal "GND7")
		(2 "B.Cu" signal "BOTTOM")
		(9 "F.Adhes" user "F.Adhesive")
		(11 "B.Adhes" user "B.Adhesive")
		(13 "F.Paste" user "Package Geometry/Pastemask Top")
		(15 "B.Paste" user "Package Geometry/Pastemask Bottom")
		(5 "F.SilkS" user "Ref Des/Silkscreen Top")
		(7 "B.SilkS" user "Ref Des/Silkscreen Bottom")
		(1 "F.Mask" user "Board Geometry/Soldermask Top")
		(3 "B.Mask" user "Board Geometry/Soldermask Bottom")
		(17 "Dwgs.User" user "User.Drawings")
		(19 "Cmts.User" user "User.Comments")
		(21 "Eco1.User" user "User.Eco1")
		(23 "Eco2.User" user "User.Eco2")
		(25 "Edge.Cuts" user "Board Geometry/Outline")
		(27 "Margin" user)
		(31 "F.CrtYd" user "Package Geometry/Place Bound Top")
		(29 "B.CrtYd" user "Package Geometry/Place Bound Bottom")
		(35 "F.Fab" user "Ref Des/Assembly Top")
		(33 "B.Fab" user "Ref Des/Assembly Bottom")
	)
	(footprint ""
		(layer "B.Cu")
		(at 101.894386 -261.179564)
		(property "Reference" "C2440"
			(at 0 0 0)
			(layer "B.SilkS")
			(hide yes)
			(effects
				(font
					(size 1.27 1.27)
				)
				(justify mirror)
			)
		)
		(property "Value" ""
			(at 0 0 0)
			(layer "B.Fab")
			(effects
				(font
					(size 1.27 1.27)
				)
				(justify mirror)
			)
		)
		(duplicate_pad_numbers_are_jumpers no)
		(fp_line
			(start -0.7874 -0.4064)
			(end -0.7874 0.4064)
			(stroke
				(width 0.1524)
				(type default)
			)
			(layer "B.SilkS")
		)
		(fp_line
			(start -0.7874 0.4064)
			(end 0.7874 0.4064)
			(stroke
				(width 0.1524)
				(type default)
			)
			(layer "B.SilkS")
		)
		(fp_line
			(start 0.7874 -0.4064)
			(end -0.7874 -0.4064)
			(stroke
				(width 0.1524)
				(type default)
			)
			(layer "B.SilkS")
		)
		(fp_line
			(start 0.7874 0.4064)
			(end 0.7874 -0.4064)
			(stroke
				(width 0.1524)
				(type default)
			)
			(layer "B.SilkS")
		)
		(fp_line
			(start -0.67945 -0.3048)
			(end -0.67945 0.3048)
			(stroke
				(width 0.1)
				(type default)
			)
			(layer "B.Fab")
		)
		(fp_line
			(start -0.67945 0.3048)
			(end -0.120396 0.3048)
			(stroke
				(width 0.1)
				(type default)
			)
			(layer "B.Fab")
		)
		(fp_line
			(start -0.12065 -0.3048)
			(end -0.67945 -0.3048)
			(stroke
				(width 0.1)
				(type default)
			)
			(layer "B.Fab")
		)
		(fp_line
			(start -0.12065 -0.2794)
			(end -0.12065 -0.3048)
			(stroke
				(width 0.1)
				(type default)
			)
			(layer "B.Fab")
		)
		(fp_line
			(start -0.120396 0.2794)
			(end 0.12065 0.2794)
			(stroke
				(width 0.1)
				(type default)
			)
			(layer "B.Fab")
		)
		(fp_line
			(start -0.120396 0.3048)
			(end -0.120396 0.2794)
			(stroke
				(width 0.1)
				(type default)
			)
			(layer "B.Fab")
		)
		(fp_line
			(start 0.12065 -0.305054)
			(end 0.12065 -0.2794)
			(stroke
				(width 0.1)
				(type default)
			)
			(layer "B.Fab")
		)
		(fp_line
			(start 0.12065 -0.2794)
			(end -0.12065 -0.2794)
			(stroke
				(width 0.1)
				(type default)
			)
			(layer "B.Fab")
		)
		(fp_line
			(start 0.12065 0.2794)
			(end 0.12065 0.3048)
			(stroke
				(width 0.1)
				(type default)
			)
			(layer "B.Fab")
		)
		(fp_line
			(start 0.12065 0.3048)
			(end 0.67945 0.3048)
			(stroke
				(width 0.1)
				(type default)
			)
			(layer "B.Fab")
		)
		(fp_line
			(start 0.67945 -0.305054)
			(end 0.12065 -0.305054)
			(stroke
				(width 0.1)
				(type default)
			)
			(layer "B.Fab")
		)
		(fp_line
			(start 0.67945 0.3048)
			(end 0.67945 -0.305054)
			(stroke
				(width 0.1)
				(type default)
			)
			(layer "B.Fab")
		)
		(pad "1" smd circle
			(at 0.40005 0 180)
			(size 0 0)
			(layers "B.Cu" "B.Mask" "B.Paste")
			(net "PVDDCR_SOC_P1")
		)
		(pad "2" smd circle
			(at -0.40005 0 180)
			(size 0 0)
			(layers "B.Cu" "B.Mask" "B.Paste")
			(net "GND")
		)
	)
	(footprint ""
		(layer "B.Cu")
		(at 166.24046 -190.821564)
		(property "Reference" "R109"
			(at 0 0 0)
			(layer "B.SilkS")
			(hide yes)
			(effects
				(font
					(size 1.27 1.27)
				)
				(justify mirror)
			)
		)
		(property "Value" ""
			(at 0 0 0)
			(layer "B.Fab")
			(effects
				(font
					(size 1.27 1.27)
				)
				(justify mirror)
			)
		)
		(duplicate_pad_numbers_are_jumpers no)
		(fp_line
			(start -0.7874 -0.4064)
			(end -0.7874 0.4064)
			(stroke
				(width 0.1524)
				(type default)
			)
			(layer "B.SilkS")
		)
		(fp_line
			(start -0.7874 0.4064)
			(end 0.7874 0.4064)
			(stroke
				(width 0.1524)
				(type default)
			)
			(layer "B.SilkS")
		)
		(fp_line
			(start 0.7874 -0.4064)
			(end -0.7874 -0.4064)
			(stroke
				(width 0.1524)
				(type default)
			)
			(layer "B.SilkS")
		)
		(fp_line
			(start 0.7874 0.4064)
			(end 0.7874 -0.4064)
			(stroke
				(width 0.1524)
				(type default)
			)
			(layer "B.SilkS")
		)
		(fp_line
			(start -0.67945 -0.3048)
			(end -0.67945 0.3048)
			(stroke
				(width 0.1)
				(type default)
			)
			(layer "B.Fab")
		)
		(fp_line
			(start -0.67945 0.3048)
			(end -0.120396 0.3048)
			(stroke
				(width 0.1)
				(type default)
			)
			(layer "B.Fab")
		)
		(fp_line
			(start -0.12065 -0.3048)
			(end -0.67945 -0.3048)
			(stroke
				(width 0.1)
				(type default)
			)
			(layer "B.Fab")
		)
		(fp_line
			(start -0.12065 -0.2794)
			(end -0.12065 -0.3048)
			(stroke
				(width 0.1)
				(type default)
			)
			(layer "B.Fab")
		)
		(fp_line
			(start -0.120396 0.2794)
			(end 0.12065 0.2794)
			(stroke
				(width 0.1)
				(type default)
			)
			(layer "B.Fab")
		)
		(fp_line
			(start -0.120396 0.3048)
			(end -0.120396 0.2794)
			(stroke
				(width 0.1)
				(type default)
			)
			(layer "B.Fab")
		)
		(fp_line
			(start 0.12065 -0.305054)
			(end 0.12065 -0.2794)
			(stroke
				(width 0.1)
				(type default)
			)
			(layer "B.Fab")
		)
		(fp_line
			(start 0.12065 -0.2794)
			(end -0.12065 -0.2794)
			(stroke
				(width 0.1)
				(type default)
			)
			(layer "B.Fab")
		)
		(fp_line
			(start 0.12065 0.2794)
			(end 0.12065 0.3048)
			(stroke
				(width 0.1)
				(type default)
			)
			(layer "B.Fab")
		)
		(fp_line
			(start 0.12065 0.3048)
			(end 0.67945 0.3048)
			(stroke
				(width 0.1)
				(type default)
			)
			(layer "B.Fab")
		)
		(fp_line
			(start 0.67945 -0.305054)
			(end 0.12065 -0.305054)
			(stroke
				(width 0.1)
				(type default)
			)
			(layer "B.Fab")
		)
		(fp_line
			(start 0.67945 0.3048)
			(end 0.67945 -0.305054)
			(stroke
				(width 0.1)
				(type default)
			)
			(layer "B.Fab")
		)
		(pad "1" smd circle
			(at 0.40005 0 180)
			(size 0 0)
			(layers "B.Cu" "B.Mask" "B.Paste")
			(net "P3V3")
		)
		(pad "2" smd circle
			(at -0.40005 0 180)
			(size 0 0)
			(layers "B.Cu" "B.Mask" "B.Paste")
			(net "PWRGD_CHGL_CPU1")
		)
	)
)
